# S9S_MB_2U (Grand Teton) — schematic netlist excerpt (pin names and nets, part order shuffled) for the footprints in the layout excerpt that follows; sources: Cadence DE-HDL packaged netlist, KiCad conversion of 03242023_DA0F0TMBIJ0_F0T_Motherboard_J_brd_V01_OCP.brd

PR4698  Q_RES  0 5% EMPTY  pkg 0402LF  page 282 : A = PVNN_MAIN_CPU0_FB_RC ; B = PVNN_MAIN_CPU0
R3706  Q_RES  10K 1% EMPTY  pkg 0402LF  page 233 : A = P3V3_AUX ; B = PCA9548_PCIE0_ADDR1

(kicad_pcb
	(version 20260206)
	(generator "pcbnew")
	(generator_version "10.0")
	(general
		(thickness 1.6)
		(legacy_teardrops no)
	)
	(paper "A4")
	(title_block
		(title "03242023_DA0F0TMBIJ0_F0T_Motherboard_J_brd_V01_OCP.brd")
		(comment 1 "Grand Teton / footprints 1840-1841 of 6105")
	)
	(layers
		(0 "F.Cu" signal "TOP")
		(4 "In1.Cu" signal "GND")
		(6 "In2.Cu" signal "IN1")
		(8 "In3.Cu" signal "GND1")
		(10 "In4.Cu" signal "IN2")
		(12 "In5.Cu" signal "GND2")
		(14 "In6.Cu" signal "IN3")
		(16 "In7.Cu" signal "GND3")
		(18 "In8.Cu" signal "VCC")
		(20 "In9.Cu" signal "VCC1")
		(22 "In10.Cu" signal "GND4")
		(24 "In11.Cu" signal "IN4")
		(26 "In12.Cu" signal "GND5")
		(28 "In13.Cu" signal "IN5")
		(30 "In14.Cu" signal "GND6")
		(32 "In15.Cu" signal "IN6")
		(34 "In16.Cu" signal "GND7")
		(2 "B.Cu" signal "BOTTOM")
		(9 "F.Adhes" user "F.Adhesive")
		(11 "B.Adhes" user "B.Adhesive")
		(13 "F.Paste" user "Package Geometry/Pastemask Top")
		(15 "B.Paste" user "Package Geometry/Pastemask Bottom")
		(5 "F.SilkS" user "Ref Des/Silkscreen Top")
		(7 "B.SilkS" user "Ref Des/Silkscreen Bottom")
		(1 "F.Mask" user "Board Geometry/Soldermask Top")
		(3 "B.Mask" user "Board Geometry/Soldermask Bottom")
		(17 "Dwgs.User" user "User.Drawings")
		(19 "Cmts.User" user "User.Comments")
		(21 "Eco1.User" user "User.Eco1")
		(23 "Eco2.User" user "User.Eco2")
		(25 "Edge.Cuts" user "Board Geometry/Outline")
		(27 "Margin" user)
		(31 "F.CrtYd" user "Package Geometry/Place Bound Top")
		(29 "B.CrtYd" user "Package Geometry/Place Bound Bottom")
		(35 "F.Fab" user "Ref Des/Assembly Top")
		(33 "B.Fab" user "Ref Des/Assembly Bottom")
	)
	(footprint ""
		(layer "F.Cu")
		(at 435.142386 -175.20285 90)
		(property "Reference" "PR4698"
			(at 0 0 90)
			(layer "F.SilkS")
			(hide yes)
			(effects
				(font
					(size 1.27 1.27)
				)
			)
		)
		(property "Value" ""
			(at 0 0 90)
			(layer "F.Fab")
			(effects
				(font
					(size 1.27 1.27)
				)
			)
		)
		(duplicate_pad_numbers_are_jumpers no)
		(fp_line
			(start 0.7874 -0.4064)
			(end 0.7874 0.4064)
			(stroke
				(width 0.1524)
				(type default)
			)
			(layer "F.SilkS")
		)
		(fp_line
			(start -0.7874 -0.4064)
			(end 0.7874 -0.4064)
			(stroke
				(width 0.1524)
				(type default)
			)
			(layer "F.SilkS")
		)
		(fp_line
			(start 0.7874 0.4064)
			(end -0.7874 0.4064)
			(stroke
				(width 0.1524)
				(type default)
			)
			(layer "F.SilkS")
		)
		(fp_line
			(start -0.7874 0.4064)
			(end -0.7874 -0.4064)
			(stroke
				(width 0.1524)
				(type default)
			)
			(layer "F.SilkS")
		)
		(fp_line
			(start -0.12065 -0.305054)
			(end -0.12065 -0.2794)
			(stroke
				(width 0.1)
				(type default)
			)
			(layer "F.Fab")
		)
		(fp_line
			(start -0.67945 -0.305054)
			(end -0.12065 -0.305054)
			(stroke
				(width 0.1)
				(type default)
			)
			(layer "F.Fab")
		)
		(fp_line
			(start 0.67945 -0.3048)
			(end 0.67945 0.3048)
			(stroke
				(width 0.1)
				(type default)
			)
			(layer "F.Fab")
		)
		(fp_line
			(start 0.12065 -0.3048)
			(end 0.67945 -0.3048)
			(stroke
				(width 0.1)
				(type default)
			)
			(layer "F.Fab")
		)
		(fp_line
			(start 0.12065 -0.2794)
			(end 0.12065 -0.3048)
			(stroke
				(width 0.1)
				(type default)
			)
			(layer "F.Fab")
		)
		(fp_line
			(start -0.12065 -0.2794)
			(end 0.12065 -0.2794)
			(stroke
				(width 0.1)
				(type default)
			)
			(layer "F.Fab")
		)
		(fp_line
			(start 0.120396 0.2794)
			(end -0.12065 0.2794)
			(stroke
				(width 0.1)
				(type default)
			)
			(layer "F.Fab")
		)
		(fp_line
			(start -0.12065 0.2794)
			(end -0.12065 0.3048)
			(stroke
				(width 0.1)
				(type default)
			)
			(layer "F.Fab")
		)
		(fp_line
			(start 0.67945 0.3048)
			(end 0.120396 0.3048)
			(stroke
				(width 0.1)
				(type default)
			)
			(layer "F.Fab")
		)
		(fp_line
			(start 0.120396 0.3048)
			(end 0.120396 0.2794)
			(stroke
				(width 0.1)
				(type default)
			)
			(layer "F.Fab")
		)
		(fp_line
			(start -0.12065 0.3048)
			(end -0.67945 0.3048)
			(stroke
				(width 0.1)
				(type default)
			)
			(layer "F.Fab")
		)
		(fp_line
			(start -0.67945 0.3048)
			(end -0.67945 -0.305054)
			(stroke
				(width 0.1)
				(type default)
			)
			(layer "F.Fab")
		)
		(pad "1" smd circle
			(at -0.40005 0 90)
			(size 0 0)
			(layers "F.Cu" "F.Mask" "F.Paste")
			(net "PVNN_MAIN_CPU0_FB_RC")
		)
		(pad "2" smd circle
			(at 0.40005 0 90)
			(size 0 0)
			(layers "F.Cu" "F.Mask" "F.Paste")
			(net "PVNN_MAIN_CPU0")
		)
	)
	(footprint ""
		(layer "F.Cu")
		(at 51.593496 -117.53977)
		(property "Reference" "R3706"
			(at 0 0 0)
			(layer "F.SilkS")
			(hide yes)
			(effects
				(font
					(size 1.27 1.27)
				)
			)
		)
		(property "Value" ""
			(at 0 0 0)
			(layer "F.Fab")
			(effects
				(font
					(size 1.27 1.27)
				)
			)
		)
		(duplicate_pad_numbers_are_jumpers no)
		(fp_line
			(start -0.7874 -0.4064)
			(end 0.7874 -0.4064)
			(stroke
				(width 0.1524)
				(type default)
			)
			(layer "F.SilkS")
		)
		(fp_line
			(start -0.7874 0.4064)
			(end -0.7874 -0.4064)
			(stroke
				(width 0.1524)
				(type default)
			)
			(layer "F.SilkS")
		)
		(fp_line
			(start 0.7874 -0.4064)
			(end 0.7874 0.4064)
			(stroke
				(width 0.1524)
				(type default)
			)
			(layer "F.SilkS")
		)
		(fp_line
			(start 0.7874 0.4064)
			(end -0.7874 0.4064)
			(stroke
				(width 0.1524)
				(type default)
			)
			(layer "F.SilkS")
		)
		(fp_line
			(start -0.67945 -0.305054)
			(end -0.12065 -0.305054)
			(stroke
				(width 0.1)
				(type default)
			)
			(layer "F.Fab")
		)
		(fp_line
			(start -0.67945 0.3048)
			(end -0.67945 -0.305054)
			(stroke
				(width 0.1)
				(type default)
			)
			(layer "F.Fab")
		)
		(fp_line
			(start -0.12065 -0.305054)
			(end -0.12065 -0.2794)
			(stroke
				(width 0.1)
				(type default)
			)
			(layer "F.Fab")
		)
		(fp_line
			(start -0.12065 -0.2794)
			(end 0.12065 -0.2794)
			(stroke
				(width 0.1)
				(type default)
			)
			(layer "F.Fab")
		)
		(fp_line
			(start -0.12065 0.2794)
			(end -0.12065 0.3048)
			(stroke
				(width 0.1)
				(type default)
			)
			(layer "F.Fab")
		)
		(fp_line
			(start -0.12065 0.3048)
			(end -0.67945 0.3048)
			(stroke
				(width 0.1)
				(type default)
			)
			(layer "F.Fab")
		)
		(fp_line
			(start 0.120396 0.2794)
			(end -0.12065 0.2794)
			(stroke
				(width 0.1)
				(type default)
			)
			(layer "F.Fab")
		)
		(fp_line
			(start 0.120396 0.3048)
			(end 0.120396 0.2794)
			(stroke
				(width 0.1)
				(type default)
			)
			(layer "F.Fab")
		)
		(fp_line
			(start 0.12065 -0.3048)
			(end 0.67945 -0.3048)
			(stroke
				(width 0.1)
				(type default)
			)
			(layer "F.Fab")
		)
		(fp_line
			(start 0.12065 -0.2794)
			(end 0.12065 -0.3048)
			(stroke
				(width 0.1)
				(type default)
			)
			(layer "F.Fab")
		)
		(fp_line
			(start 0.67945 -0.3048)
			(end 0.67945 0.3048)
			(stroke
				(width 0.1)
				(type default)
			)
			(layer "F.Fab")
		)
		(fp_line
			(start 0.67945 0.3048)
			(end 0.120396 0.3048)
			(stroke
				(width 0.1)
				(type default)
			)
			(layer "F.Fab")
		)
		(pad "1" smd circle
			(at -0.40005 0)
			(size 0 0)
			(layers "F.Cu" "F.Mask" "F.Paste")
			(net "P3V3_AUX")
		)
		(pad "2" smd circle
			(at 0.40005 0)
			(size 0 0)
			(layers "F.Cu" "F.Mask" "F.Paste")
			(net "PCA9548_PCIE0_ADDR1")
		)
	)
)
